# TIMECARD (Time Appliance Project (Time Card)) — schematic netlist excerpt (pin names and nets, part order shuffled) for the footprints in the layout excerpt that follows; sources: Cadence DE-HDL packaged netlist, KiCad conversion of R4006-B0001-02_R01.brd

U38  TS3A5018PWR_TSSOP16  pkg SOP16_173_P0256  page 24
  \in\  = MUX2_SEL
  NC1  = FPGA_FLASH_CLK
  NO1  = FT4232_SPI_CLK
  COM1  = FLASH_CLK
  NC2  = FPGA_FLASH_DQ0_MOSI
  NO2  = FT4232_SPI_MOSI
  COM2  = FLASH_DQ0_MOSI
  GND  = SG
  COM3  = FLASH_DQ1_MISO
  NO3  = FT4232_SPI_MISO
  NC3  = FPGA_FLASH_DQ1_MISO
  COM4  = FLASH_CS_N
  NO4  = FT4232_SPI_CS_N
  NC4  = FPGA_FLASH_CS_N
  \en*\  = UNNAMED_524_RESISTOR_I432_2
  V_P  = XP3R3V_FPGA

(kicad_pcb
	(version 20260206)
	(generator "pcbnew")
	(generator_version "10.0")
	(general
		(thickness 1.6)
		(legacy_teardrops no)
	)
	(paper "A4")
	(title_block
		(title "timecard-production-celestica-r4006 — R4006-B0001-02_R01.brd")
		(comment 1 "Time Appliance Project (Time Card) / footprints 431-431 of 1113")
	)
	(layers
		(0 "F.Cu" signal "TOP")
		(4 "In1.Cu" signal "L02_GND1")
		(6 "In2.Cu" signal "L03_SIG1")
		(8 "In3.Cu" signal "L04_GND2")
		(10 "In4.Cu" signal "L05_VCC1")
		(12 "In5.Cu" signal "L06_VCC2")
		(14 "In6.Cu" signal "L07_GND3")
		(16 "In7.Cu" signal "L08_SIG2")
		(18 "In8.Cu" signal "L09_GND4")
		(2 "B.Cu" signal "BOTTOM")
		(9 "F.Adhes" user "F.Adhesive")
		(11 "B.Adhes" user "B.Adhesive")
		(13 "F.Paste" user "Package Geometry/Pastemask Top")
		(15 "B.Paste" user "Package Geometry/Pastemask Bottom")
		(5 "F.SilkS" user "Ref Des/Silkscreen Top")
		(7 "B.SilkS" user "Ref Des/Silkscreen Bottom")
		(1 "F.Mask" user "Board Geometry/Soldermask Top")
		(3 "B.Mask" user "Board Geometry/Soldermask Bottom")
		(17 "Dwgs.User" user "User.Drawings")
		(19 "Cmts.User" user "User.Comments")
		(21 "Eco1.User" user "User.Eco1")
		(23 "Eco2.User" user "User.Eco2")
		(25 "Edge.Cuts" user "Board Geometry/Outline")
		(27 "Margin" user)
		(31 "F.CrtYd" user "Package Geometry/Place Bound Top")
		(29 "B.CrtYd" user "Package Geometry/Place Bound Bottom")
		(35 "F.Fab" user "Ref Des/Assembly Top")
		(33 "B.Fab" user "Ref Des/Assembly Bottom")
	)
	(footprint ""
		(layer "F.Cu")
		(at 108.9406 -80.1624)
		(property "Reference" "U38"
			(at -0.7366 3.49377 0)
			(unlocked yes)
			(layer "F.SilkS")
			(effects
				(font
					(size 0.7874 0.5842)
					(thickness 0.1524)
				)
			)
		)
		(property "Value" ""
			(at 0 0 0)
			(layer "F.Fab")
			(effects
				(font
					(size 1.27 1.27)
				)
			)
		)
		(property "Device Type" "TS3A5018PWR_TSSOP16-G220-10324A"
			(at 0 0.924306 0)
			(unlocked yes)
			(layer "F.Fab")
			(hide yes)
			(effects
				(font
					(size 0.7874 0.5842)
					(thickness 0.000001)
				)
			)
		)
		(property "User Part Number" "PARTNUM*"
			(at 0.254 1.940306 0)
			(unlocked yes)
			(layer "Cmts.User")
			(hide yes)
			(effects
				(font
					(size 0.7874 0.5842)
					(thickness 0.000001)
				)
			)
		)
		(duplicate_pad_numbers_are_jumpers no)
		(fp_line
			(start -4.0767 -2.7559)
			(end 4.0767 -2.7559)
			(stroke
				(width 0.1)
				(type default)
			)
			(layer "F.SilkS")
		)
		(fp_line
			(start -4.0767 2.7559)
			(end -4.0767 -2.7559)
			(stroke
				(width 0.1)
				(type default)
			)
			(layer "F.SilkS")
		)
		(fp_line
			(start 4.0767 -2.7559)
			(end 4.0767 2.7559)
			(stroke
				(width 0.1)
				(type default)
			)
			(layer "F.SilkS")
		)
		(fp_line
			(start 4.0767 2.7559)
			(end -4.0767 2.7559)
			(stroke
				(width 0.1)
				(type default)
			)
			(layer "F.SilkS")
		)
		(fp_poly
			(pts
				(arc
					(start -3.6576 -3.2766)
					(mid -4.4196 -3.2766)
					(end -3.6576 -3.2766)
				)
			)
			(stroke
				(width 0)
				(type default)
			)
			(fill yes)
			(layer "F.SilkS")
		)
		(fp_rect
			(start -4.3307 3.0099)
			(end 4.3307 -3.0099)
			(stroke
				(width 0)
				(type default)
			)
			(fill no)
			(layer "F.CrtYd")
		)
		(fp_line
			(start -2.1971 -2.5019)
			(end 2.1971 -2.5019)
			(stroke
				(width 0.1)
				(type default)
			)
			(layer "F.Fab")
		)
		(fp_line
			(start -2.1971 2.5019)
			(end -2.1971 -2.5019)
			(stroke
				(width 0.1)
				(type default)
			)
			(layer "F.Fab")
		)
		(fp_line
			(start 2.1971 -2.5019)
			(end 2.1971 2.5019)
			(stroke
				(width 0.1)
				(type default)
			)
			(layer "F.Fab")
		)
		(fp_line
			(start 2.1971 2.5019)
			(end -2.1971 2.5019)
			(stroke
				(width 0.1)
				(type default)
			)
			(layer "F.Fab")
		)
		(fp_poly
			(pts
				(arc
					(start -1.114298 -1.942084)
					(mid -1.914398 -1.942084)
					(end -1.114298 -1.942084)
				)
			)
			(stroke
				(width 0)
				(type default)
			)
			(fill yes)
			(layer "F.Fab")
		)
		(fp_text user "8"
			(at -4.572 2.25425 0)
			(unlocked yes)
			(layer "F.SilkS")
			(effects
				(font
					(size 0.635 0.4064)
					(thickness 0.1524)
				)
			)
		)
		(fp_text user "16"
			(at 4.50215 -2.6416 90)
			(unlocked yes)
			(layer "F.SilkS")
			(effects
				(font
					(size 0.635 0.4064)
					(thickness 0.1524)
				)
			)
		)
		(fp_text user "9"
			(at 4.5466 2.38125 0)
			(unlocked yes)
			(layer "F.SilkS")
			(effects
				(font
					(size 0.635 0.4064)
					(thickness 0.1524)
				)
			)
		)
		(fp_text user "8"
			(at -4.572 2.18567 0)
			(unlocked yes)
			(layer "F.Fab")
			(effects
				(font
					(size 0.7874 0.5842)
					(thickness 0.1524)
				)
			)
		)
		(fp_text user "16"
			(at 3.9624 -3.23723 0)
			(unlocked yes)
			(layer "F.Fab")
			(effects
				(font
					(size 0.7874 0.5842)
					(thickness 0.1524)
				)
			)
		)
		(fp_text user "9"
			(at 4.5466 2.31267 0)
			(unlocked yes)
			(layer "F.Fab")
			(effects
				(font
					(size 0.7874 0.5842)
					(thickness 0.1524)
				)
			)
		)
		(pad "1" smd rect
			(at -3.0353 -2.275078 90)
			(size 0.3556 1.5748)
			(layers "F.Cu" "F.Mask" "F.Paste")
			(net "MUX2_SEL")
		)
		(pad "2" smd rect
			(at -3.0353 -1.625092 90)
			(size 0.3556 1.5748)
			(layers "F.Cu" "F.Mask" "F.Paste")
			(net "FPGA_FLASH_CLK")
		)
		(pad "3" smd rect
			(at -3.0353 -0.975106 90)
			(size 0.3556 1.5748)
			(layers "F.Cu" "F.Mask" "F.Paste")
			(net "FT4232_SPI_CLK")
		)
		(pad "4" smd rect
			(at -3.0353 -0.32512 90)
			(size 0.3556 1.5748)
			(layers "F.Cu" "F.Mask" "F.Paste")
			(net "FLASH_CLK")
		)
		(pad "5" smd rect
			(at -3.0353 0.32512 90)
			(size 0.3556 1.5748)
			(layers "F.Cu" "F.Mask" "F.Paste")
			(net "FPGA_FLASH_DQ0_MOSI")
		)
		(pad "6" smd rect
			(at -3.0353 0.975106 90)
			(size 0.3556 1.5748)
			(layers "F.Cu" "F.Mask" "F.Paste")
			(net "FT4232_SPI_MOSI")
		)
		(pad "7" smd rect
			(at -3.0353 1.625092 90)
			(size 0.3556 1.5748)
			(layers "F.Cu" "F.Mask" "F.Paste")
			(net "FLASH_DQ0_MOSI")
		)
		(pad "8" smd rect
			(at -3.0353 2.275078 90)
			(size 0.3556 1.5748)
			(layers "F.Cu" "F.Mask" "F.Paste")
			(net "SG")
		)
		(pad "9" smd rect
			(at 3.0353 2.275078 90)
			(size 0.3556 1.5748)
			(layers "F.Cu" "F.Mask" "F.Paste")
			(net "FLASH_DQ1_MISO")
		)
		(pad "10" smd rect
			(at 3.0353 1.625092 90)
			(size 0.3556 1.5748)
			(layers "F.Cu" "F.Mask" "F.Paste")
			(net "FT4232_SPI_MISO")
		)
		(pad "11" smd rect
			(at 3.0353 0.975106 90)
			(size 0.3556 1.5748)
			(layers "F.Cu" "F.Mask" "F.Paste")
			(net "FPGA_FLASH_DQ1_MISO")
		)
		(pad "12" smd rect
			(at 3.0353 0.32512 90)
			(size 0.3556 1.5748)
			(layers "F.Cu" "F.Mask" "F.Paste")
			(net "FLASH_CS_N")
		)
		(pad "13" smd rect
			(at 3.0353 -0.32512 90)
			(size 0.3556 1.5748)
			(layers "F.Cu" "F.Mask" "F.Paste")
			(net "FT4232_SPI_CS_N")
		)
		(pad "14" smd rect
			(at 3.0353 -0.975106 90)
			(size 0.3556 1.5748)
			(layers "F.Cu" "F.Mask" "F.Paste")
			(net "FPGA_FLASH_CS_N")
		)
		(pad "15" smd rect
			(at 3.0353 -1.625092 90)
			(size 0.3556 1.5748)
			(layers "F.Cu" "F.Mask" "F.Paste")
			(net "UNNAMED_524_RESISTOR_I432_2")
		)
		(pad "16" smd rect
			(at 3.0353 -2.275078 90)
			(size 0.3556 1.5748)
			(layers "F.Cu" "F.Mask" "F.Paste")
			(net "XP3R3V_FPGA")
		)
	)
)
